# S9S_MB_2U (Grand Teton) — schematic netlist excerpt (pin names and nets, part order shuffled) for the footprints in the layout excerpt that follows; sources: Cadence DE-HDL packaged netlist, KiCad conversion of 03242023_DA0F0TMBIJ0_F0T_Motherboard_J_brd_V01_OCP.brd

R4041  Q_RES  1K 1% CHIP  pkg 0402LF  page 225 : A = P0V62_CPU0_ERRS_U306_VREF ; B = GND
R3997  Q_RES  0 5% EMPTY  pkg 0402LF  page 242 : A = P12V_SCM_UV_R ; B = P12V_SCM_UV

(kicad_pcb
	(version 20260206)
	(generator "pcbnew")
	(generator_version "10.0")
	(general
		(thickness 1.6)
		(legacy_teardrops no)
	)
	(paper "A4")
	(title_block
		(title "03242023_DA0F0TMBIJ0_F0T_Motherboard_J_brd_V01_OCP.brd")
		(comment 1 "Grand Teton / footprints 4149-4150 of 6105")
	)
	(layers
		(0 "F.Cu" signal "TOP")
		(4 "In1.Cu" signal "GND")
		(6 "In2.Cu" signal "IN1")
		(8 "In3.Cu" signal "GND1")
		(10 "In4.Cu" signal "IN2")
		(12 "In5.Cu" signal "GND2")
		(14 "In6.Cu" signal "IN3")
		(16 "In7.Cu" signal "GND3")
		(18 "In8.Cu" signal "VCC")
		(20 "In9.Cu" signal "VCC1")
		(22 "In10.Cu" signal "GND4")
		(24 "In11.Cu" signal "IN4")
		(26 "In12.Cu" signal "GND5")
		(28 "In13.Cu" signal "IN5")
		(30 "In14.Cu" signal "GND6")
		(32 "In15.Cu" signal "IN6")
		(34 "In16.Cu" signal "GND7")
		(2 "B.Cu" signal "BOTTOM")
		(9 "F.Adhes" user "F.Adhesive")
		(11 "B.Adhes" user "B.Adhesive")
		(13 "F.Paste" user "Package Geometry/Pastemask Top")
		(15 "B.Paste" user "Package Geometry/Pastemask Bottom")
		(5 "F.SilkS" user "Ref Des/Silkscreen Top")
		(7 "B.SilkS" user "Ref Des/Silkscreen Bottom")
		(1 "F.Mask" user "Board Geometry/Soldermask Top")
		(3 "B.Mask" user "Board Geometry/Soldermask Bottom")
		(17 "Dwgs.User" user "User.Drawings")
		(19 "Cmts.User" user "User.Comments")
		(21 "Eco1.User" user "User.Eco1")
		(23 "Eco2.User" user "User.Eco2")
		(25 "Edge.Cuts" user "Board Geometry/Outline")
		(27 "Margin" user)
		(31 "F.CrtYd" user "Package Geometry/Place Bound Top")
		(29 "B.CrtYd" user "Package Geometry/Place Bound Bottom")
		(35 "F.Fab" user "Ref Des/Assembly Top")
		(33 "B.Fab" user "Ref Des/Assembly Bottom")
	)
	(footprint ""
		(layer "F.Cu")
		(at 142.0622 -106.364278 90)
		(property "Reference" "R4041"
			(at 0 0 90)
			(layer "F.SilkS")
			(hide yes)
			(effects
				(font
					(size 1.27 1.27)
				)
			)
		)
		(property "Value" ""
			(at 0 0 90)
			(layer "F.Fab")
			(effects
				(font
					(size 1.27 1.27)
				)
			)
		)
		(duplicate_pad_numbers_are_jumpers no)
		(fp_line
			(start 0.7874 -0.4064)
			(end 0.7874 0.4064)
			(stroke
				(width 0.1524)
				(type default)
			)
			(layer "F.SilkS")
		)
		(fp_line
			(start -0.7874 -0.4064)
			(end 0.7874 -0.4064)
			(stroke
				(width 0.1524)
				(type default)
			)
			(layer "F.SilkS")
		)
		(fp_line
			(start 0.7874 0.4064)
			(end -0.7874 0.4064)
			(stroke
				(width 0.1524)
				(type default)
			)
			(layer "F.SilkS")
		)
		(fp_line
			(start -0.7874 0.4064)
			(end -0.7874 -0.4064)
			(stroke
				(width 0.1524)
				(type default)
			)
			(layer "F.SilkS")
		)
		(fp_line
			(start -0.12065 -0.305054)
			(end -0.12065 -0.2794)
			(stroke
				(width 0.1)
				(type default)
			)
			(layer "F.Fab")
		)
		(fp_line
			(start -0.67945 -0.305054)
			(end -0.12065 -0.305054)
			(stroke
				(width 0.1)
				(type default)
			)
			(layer "F.Fab")
		)
		(fp_line
			(start 0.67945 -0.3048)
			(end 0.67945 0.3048)
			(stroke
				(width 0.1)
				(type default)
			)
			(layer "F.Fab")
		)
		(fp_line
			(start 0.12065 -0.3048)
			(end 0.67945 -0.3048)
			(stroke
				(width 0.1)
				(type default)
			)
			(layer "F.Fab")
		)
		(fp_line
			(start 0.12065 -0.2794)
			(end 0.12065 -0.3048)
			(stroke
				(width 0.1)
				(type default)
			)
			(layer "F.Fab")
		)
		(fp_line
			(start -0.12065 -0.2794)
			(end 0.12065 -0.2794)
			(stroke
				(width 0.1)
				(type default)
			)
			(layer "F.Fab")
		)
		(fp_line
			(start 0.120396 0.2794)
			(end -0.12065 0.2794)
			(stroke
				(width 0.1)
				(type default)
			)
			(layer "F.Fab")
		)
		(fp_line
			(start -0.12065 0.2794)
			(end -0.12065 0.3048)
			(stroke
				(width 0.1)
				(type default)
			)
			(layer "F.Fab")
		)
		(fp_line
			(start 0.67945 0.3048)
			(end 0.120396 0.3048)
			(stroke
				(width 0.1)
				(type default)
			)
			(layer "F.Fab")
		)
		(fp_line
			(start 0.120396 0.3048)
			(end 0.120396 0.2794)
			(stroke
				(width 0.1)
				(type default)
			)
			(layer "F.Fab")
		)
		(fp_line
			(start -0.12065 0.3048)
			(end -0.67945 0.3048)
			(stroke
				(width 0.1)
				(type default)
			)
			(layer "F.Fab")
		)
		(fp_line
			(start -0.67945 0.3048)
			(end -0.67945 -0.305054)
			(stroke
				(width 0.1)
				(type default)
			)
			(layer "F.Fab")
		)
		(pad "1" smd circle
			(at -0.40005 0 90)
			(size 0 0)
			(layers "F.Cu" "F.Mask" "F.Paste")
			(net "P0V62_CPU0_ERRS_U306_VREF")
		)
		(pad "2" smd circle
			(at 0.40005 0 90)
			(size 0 0)
			(layers "F.Cu" "F.Mask" "F.Paste")
			(net "GND")
		)
	)
	(footprint ""
		(layer "F.Cu")
		(at 184.183782 -40.840152 180)
		(property "Reference" "R3997"
			(at 0 0 180)
			(layer "F.SilkS")
			(hide yes)
			(effects
				(font
					(size 1.27 1.27)
				)
			)
		)
		(property "Value" ""
			(at 0 0 180)
			(layer "F.Fab")
			(effects
				(font
					(size 1.27 1.27)
				)
			)
		)
		(duplicate_pad_numbers_are_jumpers no)
		(fp_line
			(start 0.7874 0.4064)
			(end -0.7874 0.4064)
			(stroke
				(width 0.1524)
				(type default)
			)
			(layer "F.SilkS")
		)
		(fp_line
			(start 0.7874 -0.4064)
			(end 0.7874 0.4064)
			(stroke
				(width 0.1524)
				(type default)
			)
			(layer "F.SilkS")
		)
		(fp_line
			(start -0.7874 0.4064)
			(end -0.7874 -0.4064)
			(stroke
				(width 0.1524)
				(type default)
			)
			(layer "F.SilkS")
		)
		(fp_line
			(start -0.7874 -0.4064)
			(end 0.7874 -0.4064)
			(stroke
				(width 0.1524)
				(type default)
			)
			(layer "F.SilkS")
		)
		(fp_line
			(start 0.67945 0.3048)
			(end 0.120396 0.3048)
			(stroke
				(width 0.1)
				(type default)
			)
			(layer "F.Fab")
		)
		(fp_line
			(start 0.67945 -0.3048)
			(end 0.67945 0.3048)
			(stroke
				(width 0.1)
				(type default)
			)
			(layer "F.Fab")
		)
		(fp_line
			(start 0.12065 -0.2794)
			(end 0.12065 -0.3048)
			(stroke
				(width 0.1)
				(type default)
			)
			(layer "F.Fab")
		)
		(fp_line
			(start 0.12065 -0.3048)
			(end 0.67945 -0.3048)
			(stroke
				(width 0.1)
				(type default)
			)
			(layer "F.Fab")
		)
		(fp_line
			(start 0.120396 0.3048)
			(end 0.120396 0.2794)
			(stroke
				(width 0.1)
				(type default)
			)
			(layer "F.Fab")
		)
		(fp_line
			(start 0.120396 0.2794)
			(end -0.12065 0.2794)
			(stroke
				(width 0.1)
				(type default)
			)
			(layer "F.Fab")
		)
		(fp_line
			(start -0.12065 0.3048)
			(end -0.67945 0.3048)
			(stroke
				(width 0.1)
				(type default)
			)
			(layer "F.Fab")
		)
		(fp_line
			(start -0.12065 0.2794)
			(end -0.12065 0.3048)
			(stroke
				(width 0.1)
				(type default)
			)
			(layer "F.Fab")
		)
		(fp_line
			(start -0.12065 -0.2794)
			(end 0.12065 -0.2794)
			(stroke
				(width 0.1)
				(type default)
			)
			(layer "F.Fab")
		)
		(fp_line
			(start -0.12065 -0.305054)
			(end -0.12065 -0.2794)
			(stroke
				(width 0.1)
				(type default)
			)
			(layer "F.Fab")
		)
		(fp_line
			(start -0.67945 0.3048)
			(end -0.67945 -0.305054)
			(stroke
				(width 0.1)
				(type default)
			)
			(layer "F.Fab")
		)
		(fp_line
			(start -0.67945 -0.305054)
			(end -0.12065 -0.305054)
			(stroke
				(width 0.1)
				(type default)
			)
			(layer "F.Fab")
		)
		(pad "1" smd circle
			(at -0.40005 0 180)
			(size 0 0)
			(layers "F.Cu" "F.Mask" "F.Paste")
			(net "P12V_SCM_UV_R")
		)
		(pad "2" smd circle
			(at 0.40005 0 180)
			(size 0 0)
			(layers "F.Cu" "F.Mask" "F.Paste")
			(net "P12V_SCM_UV")
		)
	)
)
